(kicad_pcb
	(version 20241229)
	(generator "pcbnew")
	(generator_version "9.0")
	(general
		(thickness 1.294)
		(legacy_teardrops no)
	)
	(paper "A3")
	(title_block
		(title "Kintex 410T devboard")
		(date "2024-04-03")
		(rev "1.1.2")
		(comment 9 "footprints 865-869 of 975")
	)
	(layers
		(0 "F.Cu" mixed)
		(4 "In1.Cu" power)
		(6 "In2.Cu" power)
		(8 "In3.Cu" mixed)
		(10 "In4.Cu" power)
		(12 "In5.Cu" mixed)
		(14 "In6.Cu" power)
		(16 "In7.Cu" mixed)
		(18 "In8.Cu" power)
		(2 "B.Cu" mixed)
		(9 "F.Adhes" user "F.Adhesive")
		(11 "B.Adhes" user "B.Adhesive")
		(13 "F.Paste" user)
		(15 "B.Paste" user)
		(5 "F.SilkS" user "F.Silkscreen")
		(7 "B.SilkS" user "B.Silkscreen")
		(1 "F.Mask" user)
		(3 "B.Mask" user)
		(17 "Dwgs.User" user "User.Drawings")
		(19 "Cmts.User" user "User.Comments")
		(21 "Eco1.User" user "User.Eco1")
		(23 "Eco2.User" user "User.Eco2")
		(25 "Edge.Cuts" user)
		(27 "Margin" user)
		(31 "F.CrtYd" user "F.Courtyard")
		(29 "B.CrtYd" user "B.Courtyard")
		(35 "F.Fab" user)
		(33 "B.Fab" user)
	)
	(footprint "antmicro-footprints:C_0603_1608Metric"
		(layer "B.Cu")
		(at 198.025 130)
		(descr "Capacitor SMD 0603")
		(tags "capacitor 0603")
		(property "Reference" "C379"
			(at 23.575 -28.125 0)
			(layer "B.SilkS")
			(effects
				(font
					(size 0.7 0.7)
					(thickness 0.15)
				)
				(justify right bottom mirror)
			)
		)
		(property "Value" "C_47u_0603"
			(at 0 -1.6 0)
			(layer "B.Fab")
			(effects
				(font
					(size 0.7 0.7)
					(thickness 0.15)
				)
				(justify right bottom mirror)
			)
		)
		(property "Description" "SMD Multilayer Ceramic Capacitor, 47 µF, 6.3 V, 0603 [1608 Metric], ± 20%, X5R, GRM Series"
			(at 0 0 0)
			(layer "F.Fab")
			(hide yes)
			(effects
				(font
					(size 1.27 1.27)
					(thickness 0.15)
				)
			)
		)
		(property "Author" "Antmicro"
			(at 0 0 0)
			(layer "B.Fab")
			(hide yes)
			(effects
				(font
					(size 1 1)
					(thickness 0.15)
				)
				(justify mirror)
			)
		)
		(property "Dielectric" ""
			(at 0 0 0)
			(layer "B.Fab")
			(hide yes)
			(effects
				(font
					(size 1 1)
					(thickness 0.15)
				)
				(justify mirror)
			)
		)
		(property "License" "Apache-2.0"
			(at 0 0 0)
			(layer "B.Fab")
			(hide yes)
			(effects
				(font
					(size 1 1)
					(thickness 0.15)
				)
				(justify mirror)
			)
		)
		(property "MPN" "GRM188R60J476ME15D"
			(at 0 0 0)
			(layer "B.Fab")
			(hide yes)
			(effects
				(font
					(size 1 1)
					(thickness 0.15)
				)
				(justify mirror)
			)
		)
		(property "Manufacturer" "Murata"
			(at 0 0 0)
			(layer "B.Fab")
			(hide yes)
			(effects
				(font
					(size 1 1)
					(thickness 0.15)
				)
				(justify mirror)
			)
		)
		(property "Val" "47u"
			(at 0 0 0)
			(layer "B.Fab")
			(hide yes)
			(effects
				(font
					(size 1 1)
					(thickness 0.15)
				)
				(justify mirror)
			)
		)
		(property "Voltage" ""
			(at 0 0 0)
			(layer "B.Fab")
			(hide yes)
			(effects
				(font
					(size 1 1)
					(thickness 0.15)
				)
				(justify mirror)
			)
		)
		(sheetname "FPGA supply")
		(sheetfile "fpga-supply.kicad_sch")
		(attr smd)
		(fp_line
			(start -0.15 -0.4)
			(end 0.15 -0.4)
			(stroke
				(width 0.15)
				(type solid)
			)
			(layer "B.SilkS")
		)
		(fp_line
			(start -0.15 0.4)
			(end 0.15 0.4)
			(stroke
				(width 0.15)
				(type solid)
			)
			(layer "B.SilkS")
		)
		(fp_rect
			(start -1.25 0.65)
			(end 1.25 -0.65)
			(stroke
				(width 0.05)
				(type solid)
			)
			(fill no)
			(layer "B.CrtYd")
		)
		(fp_rect
			(start -0.8 0.4)
			(end 0.8 -0.4)
			(stroke
				(width 0.15)
				(type solid)
			)
			(fill no)
			(layer "B.Fab")
		)
		(pad "1" smd roundrect
			(at -0.7 0)
			(size 0.8 1)
			(layers "B.Cu" "B.Mask" "B.Paste")
			(roundrect_rratio 0.2)
			(net 1 "GND")
			(pintype "passive")
		)
		(pad "2" smd roundrect
			(at 0.7 0)
			(size 0.8 1)
			(layers "B.Cu" "B.Mask" "B.Paste")
			(roundrect_rratio 0.2)
			(net 650 "+1V0")
			(pintype "passive")
		)
	)
	(footprint "antmicro-footprints:R_0402_1005Metric"
		(layer "B.Cu")
		(at 160 185.9 -90)
		(descr "Resistor SMD 0402")
		(tags "resistor SMD 0402")
		(property "Reference" "R293"
			(at -3.6 -0.4 90)
			(layer "B.SilkS")
			(effects
				(font
					(size 0.7 0.7)
					(thickness 0.15)
				)
				(justify left bottom mirror)
			)
		)
		(property "Value" "R_47k_0402"
			(at 0 -1.4 90)
			(layer "B.Fab")
			(effects
				(font
					(size 0.7 0.7)
					(thickness 0.15)
				)
				(justify left bottom mirror)
			)
		)
		(property "Description" "SMD Chip Resistor, 47 kohm, ± 1%, 62.5 mW, 0402 [1005 Metric], Thick Film, General Purpose"
			(at 0 0 270)
			(layer "F.Fab")
			(hide yes)
			(effects
				(font
					(size 1.27 1.27)
					(thickness 0.15)
				)
			)
		)
		(property "Author" "Antmicro"
			(at -25.9 345.9 0)
			(layer "B.Fab")
			(hide yes)
			(effects
				(font
					(size 1 1)
					(thickness 0.15)
				)
				(justify mirror)
			)
		)
		(property "License" "Apache-2.0"
			(at -25.9 345.9 0)
			(layer "B.Fab")
			(hide yes)
			(effects
				(font
					(size 1 1)
					(thickness 0.15)
				)
				(justify mirror)
			)
		)
		(property "MPN" "CR0402-FX-4702GLF"
			(at -25.9 345.9 0)
			(layer "B.Fab")
			(hide yes)
			(effects
				(font
					(size 1 1)
					(thickness 0.15)
				)
				(justify mirror)
			)
		)
		(property "Manufacturer" "Bourns"
			(at -25.9 345.9 0)
			(layer "B.Fab")
			(hide yes)
			(effects
				(font
					(size 1 1)
					(thickness 0.15)
				)
				(justify mirror)
			)
		)
		(property "Tolerance" "1%"
			(at -25.9 345.9 0)
			(layer "B.Fab")
			(hide yes)
			(effects
				(font
					(size 1 1)
					(thickness 0.15)
				)
				(justify mirror)
			)
		)
		(property "Val" "47k"
			(at -25.9 345.9 0)
			(layer "B.Fab")
			(hide yes)
			(effects
				(font
					(size 1 1)
					(thickness 0.15)
				)
				(justify mirror)
			)
		)
		(sheetname "DC-DC Converters")
		(sheetfile "dc-dc.kicad_sch")
		(attr smd)
		(fp_rect
			(start -0.925 0.47)
			(end 0.925 -0.47)
			(stroke
				(width 0.05)
				(type default)
			)
			(fill no)
			(layer "B.CrtYd")
		)
		(fp_rect
			(start -0.5 0.25)
			(end 0.5 -0.25)
			(stroke
				(width 0.15)
				(type solid)
			)
			(fill no)
			(layer "B.Fab")
		)
		(pad "1" smd roundrect
			(at -0.48 0 270)
			(size 0.59 0.64)
			(layers "B.Cu" "B.Mask" "B.Paste")
			(roundrect_rratio 0.25)
			(net 577 "/DC-DC Converters/PB_CTRL.~{PB_CTRL_INT}")
			(pintype "passive")
		)
		(pad "2" smd roundrect
			(at 0.48 0 270)
			(size 0.59 0.64)
			(layers "B.Cu" "B.Mask" "B.Paste")
			(roundrect_rratio 0.25)
			(net 701 "/DC-DC Converters/PB_CTRL_OUT")
			(pintype "passive")
		)
	)
	(footprint "antmicro-footprints:NetTie-2_SMD_Pad0.127mm"
		(layer "B.Cu")
		(at 248.24 126.45 45)
		(descr "Net tie, 2 pin, 0.127mm  SMD pads")
		(tags "net tie")
		(property "Reference" "NT17"
			(at -0.128 1.345 225)
			(layer "B.SilkS")
			(hide yes)
			(effects
				(font
					(size 0.7 0.7)
					(thickness 0.15)
				)
				(justify left bottom mirror)
			)
		)
		(property "Value" "Net-Tie_2"
			(at 0 -1.199 225)
			(layer "B.Fab")
			(effects
				(font
					(size 0.7 0.7)
					(thickness 0.15)
				)
				(justify left bottom mirror)
			)
		)
		(property "Description" "Net tie, 2 pins"
			(at 0 0 45)
			(layer "F.Fab")
			(hide yes)
			(effects
				(font
					(size 1.27 1.27)
					(thickness 0.15)
				)
			)
		)
		(property "Author" "Antmicro"
			(at 162.121465 -138.49584 0)
			(layer "B.Fab")
			(hide yes)
			(effects
				(font
					(size 1 1)
					(thickness 0.15)
				)
				(justify mirror)
			)
		)
		(property "License" "Apache-2.0"
			(at 162.121465 -138.49584 0)
			(layer "B.Fab")
			(hide yes)
			(effects
				(font
					(size 1 1)
					(thickness 0.15)
				)
				(justify mirror)
			)
		)
		(property "MPN" ""
			(at 162.121465 -138.49584 0)
			(layer "B.Fab")
			(hide yes)
			(effects
				(font
					(size 1 1)
					(thickness 0.15)
				)
				(justify mirror)
			)
		)
		(property "Manufacturer" ""
			(at 162.121465 -138.49584 0)
			(layer "B.Fab")
			(hide yes)
			(effects
				(font
					(size 1 1)
					(thickness 0.15)
				)
				(justify mirror)
			)
		)
		(sheetname "FPGA Bank 12 & 13")
		(sheetfile "fpga-bank-12-13.kicad_sch")
		(attr exclude_from_pos_files)
		(net_tie_pad_groups "1, 2")
		(fp_poly
			(pts
				(xy -0.0635 0.0635) (xy 0.0625 0.0635) (xy 0.0625 -0.0635) (xy -0.0635 -0.0635)
			)
			(stroke
				(width 0)
				(type solid)
			)
			(fill yes)
			(layer "B.Cu")
		)
		(pad "1" smd roundrect
			(at -0.127001 0 225)
			(size 0.127 0.127)
			(layers "B.Cu")
			(roundrect_rratio 0.5)
			(chamfer_ratio 0)
			(chamfer top_left bottom_left)
			(net 1330 "/SUP_MCU.RX1")
			(pinfunction "1")
			(pintype "passive")
		)
		(pad "2" smd roundrect
			(at 0.125999 0 45)
			(size 0.127 0.127)
			(layers "B.Cu")
			(roundrect_rratio 0.5)
			(chamfer_ratio 0)
			(chamfer top_left bottom_left)
			(net 54 "/FPGA Bank 12 & 13/UART1.TX")
			(pinfunction "2")
			(pintype "passive")
		)
	)
	(footprint "antmicro-footprints:SOT-23-3"
		(layer "B.Cu")
		(at 223.5 124.8)
		(property "Reference" "Q12"
			(at 0.9 2.6 180)
			(layer "B.SilkS")
			(effects
				(font
					(size 0.7 0.7)
					(thickness 0.15)
				)
				(justify left bottom mirror)
			)
		)
		(property "Value" "IRLML6344TRPBF"
			(at -1.9 -2.7 180)
			(layer "B.Fab")
			(effects
				(font
					(size 0.7 0.7)
					(thickness 0.15)
				)
				(justify left bottom mirror)
			)
		)
		(property "Description" "Power MOSFET, N Channel, 30 V, 5 A, 0.022 ohm, SOT-23, Surface Mount"
			(at 0 0 0)
			(layer "F.Fab")
			(hide yes)
			(effects
				(font
					(size 1.27 1.27)
					(thickness 0.15)
				)
			)
		)
		(property "Author" "Antmicro"
			(at 0 0 0)
			(layer "B.Fab")
			(hide yes)
			(effects
				(font
					(size 1 1)
					(thickness 0.15)
				)
				(justify mirror)
			)
		)
		(property "License" "Apache-2.0"
			(at 0 0 0)
			(layer "B.Fab")
			(hide yes)
			(effects
				(font
					(size 1 1)
					(thickness 0.15)
				)
				(justify mirror)
			)
		)
		(property "MPN" "IRLML6344TRPBF"
			(at 0 0 0)
			(layer "B.Fab")
			(hide yes)
			(effects
				(font
					(size 1 1)
					(thickness 0.15)
				)
				(justify mirror)
			)
		)
		(property "Manufacturer" "Infineon"
			(at 0 0 0)
			(layer "B.Fab")
			(hide yes)
			(effects
				(font
					(size 1 1)
					(thickness 0.15)
				)
				(justify mirror)
			)
		)
		(sheetname "User GPIO + LED + button + DIP switch")
		(sheetfile "user-gpio.kicad_sch")
		(attr smd)
		(fp_line
			(start -1.45 1.35)
			(end -0.85 1.35)
			(stroke
				(width 0.15)
				(type solid)
			)
			(layer "B.SilkS")
		)
		(fp_line
			(start -0.85 1.35)
			(end -0.7 1.5)
			(stroke
				(width 0.15)
				(type solid)
			)
			(layer "B.SilkS")
		)
		(fp_line
			(start -0.7 -1.5)
			(end -0.7 -1.35)
			(stroke
				(width 0.15)
				(type solid)
			)
			(layer "B.SilkS")
		)
		(fp_line
			(start 0.7 -1.5)
			(end -0.7 -1.5)
			(stroke
				(width 0.15)
				(type solid)
			)
			(layer "B.SilkS")
		)
		(fp_line
			(start 0.7 -0.4)
			(end 0.7 -1.5)
			(stroke
				(width 0.15)
				(type solid)
			)
			(layer "B.SilkS")
		)
		(fp_line
			(start 0.7 0.4)
			(end 0.7 1.5)
			(stroke
				(width 0.15)
				(type solid)
			)
			(layer "B.SilkS")
		)
		(fp_line
			(start 0.7 1.5)
			(end -0.7 1.5)
			(stroke
				(width 0.15)
				(type solid)
			)
			(layer "B.SilkS")
		)
		(fp_line
			(start -1.75 -1.4)
			(end -1.75 -0.5)
			(stroke
				(width 0.05)
				(type solid)
			)
			(layer "B.CrtYd")
		)
		(fp_line
			(start -1.75 -0.5)
			(end -0.85 -0.5)
			(stroke
				(width 0.05)
				(type solid)
			)
			(layer "B.CrtYd")
		)
		(fp_line
			(start -1.75 0.5)
			(end -1.75 1.4)
			(stroke
				(width 0.05)
				(type solid)
			)
			(layer "B.CrtYd")
		)
		(fp_line
			(start -0.9 1.4)
			(end -1.75 1.4)
			(stroke
				(width 0.05)
				(type solid)
			)
			(layer "B.CrtYd")
		)
		(fp_line
			(start -0.9 1.6)
			(end -0.9 1.4)
			(stroke
				(width 0.05)
				(type solid)
			)
			(layer "B.CrtYd")
		)
		(fp_line
			(start -0.9 1.6)
			(end 0.825 1.6)
			(stroke
				(width 0.05)
				(type solid)
			)
			(layer "B.CrtYd")
		)
		(fp_line
			(start -0.85 -1.65)
			(end -0.85 -1.4)
			(stroke
				(width 0.05)
				(type solid)
			)
			(layer "B.CrtYd")
		)
		(fp_line
			(start -0.85 -1.4)
			(end -1.75 -1.4)
			(stroke
				(width 0.05)
				(type solid)
			)
			(layer "B.CrtYd")
		)
		(fp_line
			(start -0.85 -0.5)
			(end -0.85 0.5)
			(stroke
				(width 0.05)
				(type solid)
			)
			(layer "B.CrtYd")
		)
		(fp_line
			(start -0.85 0.5)
			(end -1.75 0.5)
			(stroke
				(width 0.05)
				(type solid)
			)
			(layer "B.CrtYd")
		)
		(fp_line
			(start 0.825 0.45)
			(end 1.75 0.45)
			(stroke
				(width 0.05)
				(type solid)
			)
			(layer "B.CrtYd")
		)
		(fp_line
			(start 0.825 1.6)
			(end 0.825 0.45)
			(stroke
				(width 0.05)
				(type solid)
			)
			(layer "B.CrtYd")
		)
		(fp_line
			(start 0.85 -1.65)
			(end -0.85 -1.65)
			(stroke
				(width 0.05)
				(type solid)
			)
			(layer "B.CrtYd")
		)
		(fp_line
			(start 0.85 -0.45)
			(end 0.85 -1.65)
			(stroke
				(width 0.05)
				(type solid)
			)
			(layer "B.CrtYd")
		)
		(fp_line
			(start 1.75 -0.45)
			(end 0.85 -0.45)
			(stroke
				(width 0.05)
				(type solid)
			)
			(layer "B.CrtYd")
		)
		(fp_line
			(start 1.75 0.45)
			(end 1.75 -0.45)
			(stroke
				(width 0.05)
				(type solid)
			)
			(layer "B.CrtYd")
		)
		(fp_line
			(start -0.712 -1.519)
			(end 0.688 -1.519)
			(stroke
				(width 0.15)
				(type solid)
			)
			(layer "B.Fab")
		)
		(fp_line
			(start -0.712 1.325)
			(end -0.712 -1.523)
			(stroke
				(width 0.15)
				(type solid)
			)
			(layer "B.Fab")
		)
		(fp_line
			(start -0.437 1.526)
			(end -0.712 1.325)
			(stroke
				(width 0.15)
				(type solid)
			)
			(layer "B.Fab")
		)
		(fp_line
			(start -0.437 1.526)
			(end 0.688 1.526)
			(stroke
				(width 0.15)
				(type solid)
			)
			(layer "B.Fab")
		)
		(fp_line
			(start 0.688 -1.519)
			(end 0.688 1.52)
			(stroke
				(width 0.15)
				(type solid)
			)
			(layer "B.Fab")
		)
		(pad "1" smd roundrect
			(at -1.1 0.951)
			(size 1 0.6)
			(layers "B.Cu" "B.Mask" "B.Paste")
			(roundrect_rratio 0.15)
			(net 876 "/User GPIO + LED + button + DIP switch/FAN_PWM_CTRL_AON")
			(pinfunction "G")
			(pintype "bidirectional")
		)
		(pad "2" smd roundrect
			(at -1.1 -0.949)
			(size 1 0.6)
			(layers "B.Cu" "B.Mask" "B.Paste")
			(roundrect_rratio 0.15)
			(net 1 "GND")
			(pinfunction "S")
			(pintype "bidirectional")
		)
		(pad "3" smd roundrect
			(at 1.1 0.0005)
			(size 1 0.6)
			(layers "B.Cu" "B.Mask" "B.Paste")
			(roundrect_rratio 0.15)
			(net 801 "/User GPIO + LED + button + DIP switch/FAN_PWM_PIN")
			(pinfunction "D")
			(pintype "bidirectional")
		)
	)
	(footprint "antmicro-footprints:R_0402_1005Metric"
		(layer "B.Cu")
		(at 219.753 149.216 180)
		(descr "Resistor SMD 0402")
		(tags "resistor SMD 0402")
		(property "Reference" "R225"
			(at 0.753 -0.409 0)
			(layer "B.SilkS")
			(effects
				(font
					(size 0.7 0.7)
					(thickness 0.15)
				)
				(justify left bottom mirror)
			)
		)
		(property "Value" "R_2k2_0402"
			(at 0 -1.4 0)
			(layer "B.Fab")
			(effects
				(font
					(size 0.7 0.7)
					(thickness 0.15)
				)
				(justify left bottom mirror)
			)
		)
		(property "Description" "SMD Chip Resistor, 2.2 kohm, ± 1%, 62.5 mW, 0402 [1005 Metric], Thick Film, General Purpose"
			(at 0 0 180)
			(layer "F.Fab")
			(hide yes)
			(effects
				(font
					(size 1.27 1.27)
					(thickness 0.15)
				)
			)
		)
		(property "Author" "Antmicro"
			(at 439.506 298.432 0)
			(layer "B.Fab")
			(hide yes)
			(effects
				(font
					(size 1 1)
					(thickness 0.15)
				)
				(justify mirror)
			)
		)
		(property "DNP" "DNP"
			(at 439.506 298.432 0)
			(layer "B.Fab")
			(hide yes)
			(effects
				(font
					(size 1 1)
					(thickness 0.15)
				)
				(justify mirror)
			)
		)
		(property "License" "Apache-2.0"
			(at 439.506 298.432 0)
			(layer "B.Fab")
			(hide yes)
			(effects
				(font
					(size 1 1)
					(thickness 0.15)
				)
				(justify mirror)
			)
		)
		(property "MPN" "CR0402-FX-2201GLF"
			(at 439.506 298.432 0)
			(layer "B.Fab")
			(hide yes)
			(effects
				(font
					(size 1 1)
					(thickness 0.15)
				)
				(justify mirror)
			)
		)
		(property "Manufacturer" "Bourns"
			(at 439.506 298.432 0)
			(layer "B.Fab")
			(hide yes)
			(effects
				(font
					(size 1 1)
					(thickness 0.15)
				)
				(justify mirror)
			)
		)
		(property "Tolerance" "1%"
			(at 439.506 298.432 0)
			(layer "B.Fab")
			(hide yes)
			(effects
				(font
					(size 1 1)
					(thickness 0.15)
				)
				(justify mirror)
			)
		)
		(property "Val" "2k2"
			(at 439.506 298.432 0)
			(layer "B.Fab")
			(hide yes)
			(effects
				(font
					(size 1 1)
					(thickness 0.15)
				)
				(justify mirror)
			)
		)
		(property "dnp" ""
			(at 439.506 298.432 0)
			(layer "B.Fab")
			(hide yes)
			(effects
				(font
					(size 1 1)
					(thickness 0.15)
				)
				(justify mirror)
			)
		)
		(property "exclude_from_bom" ""
			(at 439.506 298.432 0)
			(layer "B.Fab")
			(hide yes)
			(effects
				(font
					(size 1 1)
					(thickness 0.15)
				)
				(justify mirror)
			)
		)
		(sheetname "HDMI + Ethernet")
		(sheetfile "hdmi-ethernet.kicad_sch")
		(attr smd exclude_from_bom)
		(fp_rect
			(start -0.925 0.47)
			(end 0.925 -0.47)
			(stroke
				(width 0.05)
				(type default)
			)
			(fill no)
			(layer "B.CrtYd")
		)
		(fp_rect
			(start -0.5 0.25)
			(end 0.5 -0.25)
			(stroke
				(width 0.15)
				(type solid)
			)
			(fill no)
			(layer "B.Fab")
		)
		(pad "1" smd roundrect
			(at -0.48 0 180)
			(size 0.59 0.64)
			(layers "B.Cu" "B.Mask" "B.Paste")
			(roundrect_rratio 0.25)
			(net 944 "/HDMI + Ethernet/ETH_PHY_RX_DV")
			(pintype "passive")
		)
		(pad "2" smd roundrect
			(at 0.48 0 180)
			(size 0.59 0.64)
			(layers "B.Cu" "B.Mask" "B.Paste")
			(roundrect_rratio 0.25)
			(net 1 "GND")
			(pintype "passive")
		)
	)
)
